# BASEBOARD_FAB2 (Tioga Pass) — schematic netlist excerpt (pin names and nets, part order shuffled) for the footprints in the layout excerpt that follows; sources: Cadence DE-HDL packaged netlist, KiCad conversion of Wiwynn_Tioga_Pass_MB.brd

C5D15  CAP_A  22.0UF 4V 20% X6S  pkg 0603V  page 42 : A = PVCCIN_CPU0 ; B = GND
RN8F1  RES  4.75K 1% CHIP  pkg 0402  page 137 : A = P3V3_STBY ; B = PU_SPI_BMC_BT_CS0_N
C8A7  CAP_A  1.0UF 6.3V 10% X6S  pkg 0402V  page 235 : A = VR_PVNN_P1V05_PCH_VD12 ; B = GND

(kicad_pcb
	(version 20260206)
	(generator "pcbnew")
	(generator_version "10.0")
	(general
		(thickness 1.6)
		(legacy_teardrops no)
	)
	(paper "A4")
	(title_block
		(title "Wiwynn_Tioga_Pass_MB.brd")
		(comment 1 "Tioga Pass / footprints 556-558 of 4770")
	)
	(layers
		(0 "F.Cu" signal "TOP")
		(4 "In1.Cu" signal "L2GND")
		(6 "In2.Cu" signal "L3")
		(8 "In3.Cu" signal "L4GND")
		(10 "In4.Cu" signal "L5")
		(12 "In5.Cu" signal "L6GND")
		(14 "In6.Cu" signal "L7VCC")
		(16 "In7.Cu" signal "L8VCC")
		(18 "In8.Cu" signal "L9GND")
		(20 "In9.Cu" signal "L10")
		(22 "In10.Cu" signal "L11GND")
		(24 "In11.Cu" signal "L12")
		(26 "In12.Cu" signal "L13GND")
		(2 "B.Cu" signal "BOTTOM")
		(9 "F.Adhes" user "F.Adhesive")
		(11 "B.Adhes" user "B.Adhesive")
		(13 "F.Paste" user "Package Geometry/Pastemask Top")
		(15 "B.Paste" user "Package Geometry/Pastemask Bottom")
		(5 "F.SilkS" user "Ref Des/Silkscreen Top")
		(7 "B.SilkS" user "Ref Des/Silkscreen Bottom")
		(1 "F.Mask" user "Board Geometry/Soldermask Top")
		(3 "B.Mask" user "Board Geometry/Soldermask Bottom")
		(17 "Dwgs.User" user "User.Drawings")
		(19 "Cmts.User" user "User.Comments")
		(21 "Eco1.User" user "User.Eco1")
		(23 "Eco2.User" user "User.Eco2")
		(25 "Edge.Cuts" user "Board Geometry/Outline")
		(27 "Margin" user)
		(31 "F.CrtYd" user "Package Geometry/Place Bound Top")
		(29 "B.CrtYd" user "Package Geometry/Place Bound Bottom")
		(35 "F.Fab" user "Ref Des/Assembly Top")
		(33 "B.Fab" user "Ref Des/Assembly Bottom")
	)
	(footprint ""
		(layer "F.Cu")
		(at 455.217784 -1.539494 90)
		(property "Reference" "RN8F1"
			(at -0.8382 -0.67818 90)
			(unlocked yes)
			(layer "F.SilkS")
			(effects
				(font
					(size 0.4064 0.254)
					(thickness 0.1524)
				)
				(justify left)
			)
		)
		(property "Value" ""
			(at 0 0 90)
			(layer "F.Fab")
			(effects
				(font
					(size 1.27 1.27)
				)
			)
		)
		(duplicate_pad_numbers_are_jumpers no)
		(fp_poly
			(pts
				(xy -0.2794 -0.1016) (xy 0.2794 -0.1016) (xy 0.2794 0.9906) (xy -0.2794 0.9906)
			)
			(stroke
				(width 0)
				(type default)
			)
			(fill no)
			(layer "F.CrtYd")
		)
		(fp_line
			(start 0.2794 -0.1016)
			(end -0.2794 -0.1016)
			(stroke
				(width 0.1)
				(type default)
			)
			(layer "F.Fab")
		)
		(fp_line
			(start -0.2794 -0.1016)
			(end -0.2794 0.9906)
			(stroke
				(width 0.1)
				(type default)
			)
			(layer "F.Fab")
		)
		(fp_line
			(start 0.2794 0.9906)
			(end 0.2794 -0.1016)
			(stroke
				(width 0.1)
				(type default)
			)
			(layer "F.Fab")
		)
		(fp_line
			(start -0.2794 0.9906)
			(end 0.2794 0.9906)
			(stroke
				(width 0.1)
				(type default)
			)
			(layer "F.Fab")
		)
		(pad "1" smd rect
			(at 0 0 90)
			(size 0.508 0.508)
			(layers "F.Cu" "F.Mask" "F.Paste")
			(net "P3V3_STBY")
		)
		(pad "2" smd rect
			(at 0 0.889 90)
			(size 0.508 0.508)
			(layers "F.Cu" "F.Mask" "F.Paste")
			(net "PU_SPI_BMC_BT_CS0_N")
		)
		(zone
			(layer "F.Cu")
			(hatch none 0.5)
			(connect_pads
				(clearance 0)
			)
			(min_thickness 0.25)
			(keepout
				(tracks allowed)
				(vias not_allowed)
				(pads allowed)
				(copperpour not_allowed)
				(footprints allowed)
			)
			(placement
				(enabled no)
				(sheetname "")
			)
			(fill
				(thermal_gap 0.5)
				(thermal_bridge_width 0.5)
				(island_removal_mode 0)
			)
			(polygon
				(pts
					(xy 455.471784 -1.285494) (xy 455.471784 -1.793494) (xy 455.852784 -1.793494) (xy 455.852784 -1.285494)
				)
			)
		)
		(zone
			(layer "F.Cu")
			(hatch none 0.5)
			(connect_pads
				(clearance 0)
			)
			(min_thickness 0.25)
			(keepout
				(tracks not_allowed)
				(vias allowed)
				(pads allowed)
				(copperpour not_allowed)
				(footprints allowed)
			)
			(placement
				(enabled no)
				(sheetname "")
			)
			(fill
				(thermal_gap 0.5)
				(thermal_bridge_width 0.5)
				(island_removal_mode 0)
			)
			(polygon
				(pts
					(xy 455.852784 -1.285494) (xy 455.852784 -1.793494) (xy 455.471784 -1.793494) (xy 455.471784 -1.285494)
				)
			)
		)
	)
	(footprint ""
		(layer "F.Cu")
		(at 263.1948 -79.6036 180)
		(property "Reference" "C5D15"
			(at 0 0 180)
			(layer "F.SilkS")
			(hide yes)
			(effects
				(font
					(size 1.27 1.27)
				)
			)
		)
		(property "Value" ""
			(at 0 0 180)
			(layer "F.Fab")
			(effects
				(font
					(size 1.27 1.27)
				)
			)
		)
		(duplicate_pad_numbers_are_jumpers no)
		(fp_poly
			(pts
				(xy -0.4953 -0.2032) (xy 0.4953 -0.2032) (xy 0.4953 1.6002) (xy -0.4953 1.6002)
			)
			(stroke
				(width 0)
				(type default)
			)
			(fill no)
			(layer "F.CrtYd")
		)
		(fp_line
			(start 0.4953 1.6002)
			(end -0.4953 1.6002)
			(stroke
				(width 0.1)
				(type default)
			)
			(layer "F.Fab")
		)
		(fp_line
			(start 0.4953 -0.2032)
			(end 0.4953 1.6002)
			(stroke
				(width 0.1)
				(type default)
			)
			(layer "F.Fab")
		)
		(fp_line
			(start -0.4953 1.6002)
			(end -0.4953 -0.2032)
			(stroke
				(width 0.1)
				(type default)
			)
			(layer "F.Fab")
		)
		(fp_line
			(start -0.4953 -0.2032)
			(end 0.4953 -0.2032)
			(stroke
				(width 0.1)
				(type default)
			)
			(layer "F.Fab")
		)
		(pad "1" smd rect
			(at 0 0 180)
			(size 0.762 0.889)
			(layers "F.Cu" "F.Mask" "F.Paste")
			(net "PVCCIN_CPU0")
		)
		(pad "2" smd rect
			(at 0 1.397 180)
			(size 0.762 0.889)
			(layers "F.Cu" "F.Mask" "F.Paste")
			(net "GND")
		)
		(zone
			(layer "F.Cu")
			(hatch none 0.5)
			(connect_pads
				(clearance 0)
			)
			(min_thickness 0.25)
			(keepout
				(tracks not_allowed)
				(vias allowed)
				(pads allowed)
				(copperpour not_allowed)
				(footprints allowed)
			)
			(placement
				(enabled no)
				(sheetname "")
			)
			(fill
				(thermal_gap 0.5)
				(thermal_bridge_width 0.5)
				(island_removal_mode 0)
			)
			(polygon
				(pts
					(xy 263.5758 -80.0481) (xy 262.8138 -80.0481) (xy 262.8138 -80.5561) (xy 263.5758 -80.5561)
				)
			)
		)
	)
	(footprint ""
		(layer "F.Cu")
		(at 390.906 -151.236426)
		(property "Reference" "C8A7"
			(at 0 0 0)
			(layer "F.SilkS")
			(hide yes)
			(effects
				(font
					(size 1.27 1.27)
				)
			)
		)
		(property "Value" ""
			(at 0 0 0)
			(layer "F.Fab")
			(effects
				(font
					(size 1.27 1.27)
				)
			)
		)
		(duplicate_pad_numbers_are_jumpers no)
		(fp_poly
			(pts
				(xy 0.3048 -0.1016) (xy 0.3048 0.9906) (xy -0.3048 0.9906) (xy -0.3048 -0.1016)
			)
			(stroke
				(width 0)
				(type default)
			)
			(fill no)
			(layer "F.CrtYd")
		)
		(fp_line
			(start -0.3048 -0.1016)
			(end -0.3048 0.9906)
			(stroke
				(width 0.1)
				(type default)
			)
			(layer "F.Fab")
		)
		(fp_line
			(start -0.3048 0.9906)
			(end 0.3048 0.9906)
			(stroke
				(width 0.1)
				(type default)
			)
			(layer "F.Fab")
		)
		(fp_line
			(start 0.3048 -0.1016)
			(end -0.3048 -0.1016)
			(stroke
				(width 0.1)
				(type default)
			)
			(layer "F.Fab")
		)
		(fp_line
			(start 0.3048 0.9906)
			(end 0.3048 -0.1016)
			(stroke
				(width 0.1)
				(type default)
			)
			(layer "F.Fab")
		)
		(pad "1" smd rect
			(at 0 0)
			(size 0.508 0.508)
			(layers "F.Cu" "F.Mask" "F.Paste")
			(net "VR_PVNN_P1V05_PCH_VD12")
		)
		(pad "2" smd rect
			(at 0 0.889)
			(size 0.508 0.508)
			(layers "F.Cu" "F.Mask" "F.Paste")
			(net "GND")
		)
		(zone
			(layer "F.Cu")
			(hatch none 0.5)
			(connect_pads
				(clearance 0)
			)
			(min_thickness 0.25)
			(keepout
				(tracks allowed)
				(vias not_allowed)
				(pads allowed)
				(copperpour not_allowed)
				(footprints allowed)
			)
			(placement
				(enabled no)
				(sheetname "")
			)
			(fill
				(thermal_gap 0.5)
				(thermal_bridge_width 0.5)
				(island_removal_mode 0)
			)
			(polygon
				(pts
					(xy 390.652 -150.982426) (xy 391.16 -150.982426) (xy 391.16 -150.601426) (xy 390.652 -150.601426)
				)
			)
		)
		(zone
			(layer "F.Cu")
			(hatch none 0.5)
			(connect_pads
				(clearance 0)
			)
			(min_thickness 0.25)
			(keepout
				(tracks not_allowed)
				(vias allowed)
				(pads allowed)
				(copperpour not_allowed)
				(footprints allowed)
			)
			(placement
				(enabled no)
				(sheetname "")
			)
			(fill
				(thermal_gap 0.5)
				(thermal_bridge_width 0.5)
				(island_removal_mode 0)
			)
			(polygon
				(pts
					(xy 390.652 -150.601426) (xy 391.16 -150.601426) (xy 391.16 -150.982426) (xy 390.652 -150.982426)
				)
			)
		)
	)
)
